# T6G (Grand Teton) — schematic netlist excerpt (pin names and nets, part order shuffled) for the footprints in the layout excerpt that follows; sources: Cadence DE-HDL packaged netlist, KiCad conversion of 04192023_DAF0TMB3IC0_F0TG_MB_C_brd_V02_OCP.brd

R6751  Q_RES  1K 1% CHIP  pkg 0201LF  page 184 : A = P1V8_CPU1_RT_1D ; B = SMB_RT_CPU1_P3_R_SCL
PC412_3  Q_CAP  22UF 16V 20% X6S  pkg C0805  page 219 : A = SW_P12V_AUX_PVDDCR_CPU1_P1_FLT ; B = GND
R789  Q_RES  0 5% EMPTY  pkg 0402LF  page 160 : A = SMB_CPU0_CPU1_APML_BUF1_SCL ; B = SMB_CPU0_CPU1_APML_BUF1_SCL_R1

(kicad_pcb
	(version 20260206)
	(generator "pcbnew")
	(generator_version "10.0")
	(general
		(thickness 1.6)
		(legacy_teardrops no)
	)
	(paper "A4")
	(title_block
		(title "04192023_DAF0TMB3IC0_F0TG_MB_C_brd_V02_OCP.brd")
		(comment 1 "Grand Teton / footprints 8224-8226 of 8354")
	)
	(layers
		(0 "F.Cu" signal "TOP")
		(4 "In1.Cu" signal "GND")
		(6 "In2.Cu" signal "IN1")
		(8 "In3.Cu" signal "GND1")
		(10 "In4.Cu" signal "IN2")
		(12 "In5.Cu" signal "GND2")
		(14 "In6.Cu" signal "IN3")
		(16 "In7.Cu" signal "GND3")
		(18 "In8.Cu" signal "VCC")
		(20 "In9.Cu" signal "VCC1")
		(22 "In10.Cu" signal "GND4")
		(24 "In11.Cu" signal "IN4")
		(26 "In12.Cu" signal "GND5")
		(28 "In13.Cu" signal "IN5")
		(30 "In14.Cu" signal "GND6")
		(32 "In15.Cu" signal "IN6")
		(34 "In16.Cu" signal "GND7")
		(2 "B.Cu" signal "BOTTOM")
		(9 "F.Adhes" user "F.Adhesive")
		(11 "B.Adhes" user "B.Adhesive")
		(13 "F.Paste" user "Package Geometry/Pastemask Top")
		(15 "B.Paste" user "Package Geometry/Pastemask Bottom")
		(5 "F.SilkS" user "Ref Des/Silkscreen Top")
		(7 "B.SilkS" user "Ref Des/Silkscreen Bottom")
		(1 "F.Mask" user "Board Geometry/Soldermask Top")
		(3 "B.Mask" user "Board Geometry/Soldermask Bottom")
		(17 "Dwgs.User" user "User.Drawings")
		(19 "Cmts.User" user "User.Comments")
		(21 "Eco1.User" user "User.Eco1")
		(23 "Eco2.User" user "User.Eco2")
		(25 "Edge.Cuts" user "Board Geometry/Outline")
		(27 "Margin" user)
		(31 "F.CrtYd" user "Package Geometry/Place Bound Top")
		(29 "B.CrtYd" user "Package Geometry/Place Bound Bottom")
		(35 "F.Fab" user "Ref Des/Assembly Top")
		(33 "B.Fab" user "Ref Des/Assembly Bottom")
	)
	(footprint ""
		(layer "B.Cu")
		(at 237.871 -227.203)
		(property "Reference" "R789"
			(at 0 0 0)
			(layer "B.SilkS")
			(hide yes)
			(effects
				(font
					(size 1.27 1.27)
				)
				(justify mirror)
			)
		)
		(property "Value" ""
			(at 0 0 0)
			(layer "B.Fab")
			(effects
				(font
					(size 1.27 1.27)
				)
				(justify mirror)
			)
		)
		(duplicate_pad_numbers_are_jumpers no)
		(fp_line
			(start -0.7874 -0.4064)
			(end -0.7874 0.4064)
			(stroke
				(width 0.1524)
				(type default)
			)
			(layer "B.SilkS")
		)
		(fp_line
			(start -0.7874 0.4064)
			(end 0.7874 0.4064)
			(stroke
				(width 0.1524)
				(type default)
			)
			(layer "B.SilkS")
		)
		(fp_line
			(start 0.7874 -0.4064)
			(end -0.7874 -0.4064)
			(stroke
				(width 0.1524)
				(type default)
			)
			(layer "B.SilkS")
		)
		(fp_line
			(start 0.7874 0.4064)
			(end 0.7874 -0.4064)
			(stroke
				(width 0.1524)
				(type default)
			)
			(layer "B.SilkS")
		)
		(fp_line
			(start -0.67945 -0.3048)
			(end -0.67945 0.3048)
			(stroke
				(width 0.1)
				(type default)
			)
			(layer "B.Fab")
		)
		(fp_line
			(start -0.67945 0.3048)
			(end -0.120396 0.3048)
			(stroke
				(width 0.1)
				(type default)
			)
			(layer "B.Fab")
		)
		(fp_line
			(start -0.12065 -0.3048)
			(end -0.67945 -0.3048)
			(stroke
				(width 0.1)
				(type default)
			)
			(layer "B.Fab")
		)
		(fp_line
			(start -0.12065 -0.2794)
			(end -0.12065 -0.3048)
			(stroke
				(width 0.1)
				(type default)
			)
			(layer "B.Fab")
		)
		(fp_line
			(start -0.120396 0.2794)
			(end 0.12065 0.2794)
			(stroke
				(width 0.1)
				(type default)
			)
			(layer "B.Fab")
		)
		(fp_line
			(start -0.120396 0.3048)
			(end -0.120396 0.2794)
			(stroke
				(width 0.1)
				(type default)
			)
			(layer "B.Fab")
		)
		(fp_line
			(start 0.12065 -0.305054)
			(end 0.12065 -0.2794)
			(stroke
				(width 0.1)
				(type default)
			)
			(layer "B.Fab")
		)
		(fp_line
			(start 0.12065 -0.2794)
			(end -0.12065 -0.2794)
			(stroke
				(width 0.1)
				(type default)
			)
			(layer "B.Fab")
		)
		(fp_line
			(start 0.12065 0.2794)
			(end 0.12065 0.3048)
			(stroke
				(width 0.1)
				(type default)
			)
			(layer "B.Fab")
		)
		(fp_line
			(start 0.12065 0.3048)
			(end 0.67945 0.3048)
			(stroke
				(width 0.1)
				(type default)
			)
			(layer "B.Fab")
		)
		(fp_line
			(start 0.67945 -0.305054)
			(end 0.12065 -0.305054)
			(stroke
				(width 0.1)
				(type default)
			)
			(layer "B.Fab")
		)
		(fp_line
			(start 0.67945 0.3048)
			(end 0.67945 -0.305054)
			(stroke
				(width 0.1)
				(type default)
			)
			(layer "B.Fab")
		)
		(pad "1" smd circle
			(at 0.40005 0 180)
			(size 0 0)
			(layers "B.Cu" "B.Mask" "B.Paste")
			(net "SMB_CPU0_CPU1_APML_BUF1_SCL")
		)
		(pad "2" smd circle
			(at -0.40005 0 180)
			(size 0 0)
			(layers "B.Cu" "B.Mask" "B.Paste")
			(net "SMB_CPU0_CPU1_APML_BUF1_SCL_R1")
		)
	)
	(footprint ""
		(layer "B.Cu")
		(at 216.027 -339.725 90)
		(property "Reference" "R6751"
			(at 0 0 90)
			(layer "B.SilkS")
			(hide yes)
			(effects
				(font
					(size 1.27 1.27)
				)
				(justify mirror)
			)
		)
		(property "Value" ""
			(at 0 0 90)
			(layer "B.Fab")
			(effects
				(font
					(size 1.27 1.27)
				)
				(justify mirror)
			)
		)
		(duplicate_pad_numbers_are_jumpers no)
		(fp_line
			(start 0.32512 -0.175006)
			(end -0.32512 -0.175006)
			(stroke
				(width 0.1)
				(type default)
			)
			(layer "B.Fab")
		)
		(fp_line
			(start -0.32512 -0.175006)
			(end -0.32512 0.175006)
			(stroke
				(width 0.1)
				(type default)
			)
			(layer "B.Fab")
		)
		(fp_line
			(start 0.32512 0.175006)
			(end 0.32512 -0.175006)
			(stroke
				(width 0.1)
				(type default)
			)
			(layer "B.Fab")
		)
		(fp_line
			(start -0.32512 0.175006)
			(end 0.32512 0.175006)
			(stroke
				(width 0.1)
				(type default)
			)
			(layer "B.Fab")
		)
		(pad "1" smd rect
			(at 0.2667 0 270)
			(size 0.3048 0.381)
			(layers "B.Cu" "B.Mask" "B.Paste")
			(net "P1V8_CPU1_RT_1D")
		)
		(pad "2" smd rect
			(at -0.2667 0 90)
			(size 0.3048 0.381)
			(layers "B.Cu" "B.Mask" "B.Paste")
			(net "SMB_RT_CPU1_P3_R_SCL")
		)
	)
	(footprint ""
		(layer "B.Cu")
		(at 73.65873 -335.06791 90)
		(property "Reference" "PC412_3"
			(at 0 0 90)
			(layer "B.SilkS")
			(hide yes)
			(effects
				(font
					(size 1.27 1.27)
				)
				(justify mirror)
			)
		)
		(property "Value" ""
			(at 0 0 90)
			(layer "B.Fab")
			(effects
				(font
					(size 1.27 1.27)
				)
				(justify mirror)
			)
		)
		(duplicate_pad_numbers_are_jumpers no)
		(fp_line
			(start 1.524 -0.762)
			(end -1.524 -0.762)
			(stroke
				(width 0.1524)
				(type default)
			)
			(layer "B.SilkS")
		)
		(fp_line
			(start -1.524 -0.762)
			(end -1.524 0.762)
			(stroke
				(width 0.1524)
				(type default)
			)
			(layer "B.SilkS")
		)
		(fp_line
			(start 1.524 0.762)
			(end 1.524 -0.762)
			(stroke
				(width 0.1524)
				(type default)
			)
			(layer "B.SilkS")
		)
		(fp_line
			(start -1.524 0.762)
			(end 1.524 0.762)
			(stroke
				(width 0.1524)
				(type default)
			)
			(layer "B.SilkS")
		)
		(fp_line
			(start 1.1049 -0.724916)
			(end 1.1049 0.724916)
			(stroke
				(width 0.1)
				(type default)
			)
			(layer "B.Fab")
		)
		(fp_line
			(start -1.1049 -0.724916)
			(end 1.1049 -0.724916)
			(stroke
				(width 0.1)
				(type default)
			)
			(layer "B.Fab")
		)
		(fp_line
			(start 1.1049 0.724916)
			(end -1.1049 0.724916)
			(stroke
				(width 0.1)
				(type default)
			)
			(layer "B.Fab")
		)
		(fp_line
			(start -1.1049 0.724916)
			(end -1.1049 -0.724916)
			(stroke
				(width 0.1)
				(type default)
			)
			(layer "B.Fab")
		)
		(pad "1" smd rect
			(at 0.889 0 90)
			(size 1.016 1.27)
			(layers "B.Cu" "B.Mask" "B.Paste")
			(net "SW_P12V_AUX_PVDDCR_CPU1_P1_FLT")
		)
		(pad "2" smd rect
			(at -0.889 0 90)
			(size 1.016 1.27)
			(layers "B.Cu" "B.Mask" "B.Paste")
			(net "GND")
		)
	)
)
